# S9S_MB_2U (Grand Teton) — schematic netlist excerpt (pin names and nets, part order shuffled) for the footprints in the layout excerpt that follows; sources: Cadence DE-HDL packaged netlist, KiCad conversion of 03242023_DA0F0TMBIJ0_F0T_Motherboard_J_brd_V01_OCP.brd

PC315  Q_CAPP  270UF 16V 20% OSCON  pkg THLF  page 267 : A = SW_P12V_PVCCIN_CPU0_FLT ; B = GND
C1337  Q_CAP  0.1UF 25V 10% X7R  pkg 0402  page 296 : A = PVNN_TERM_CPU1 ; B = GND

(kicad_pcb
	(version 20260206)
	(generator "pcbnew")
	(generator_version "10.0")
	(general
		(thickness 1.6)
		(legacy_teardrops no)
	)
	(paper "A4")
	(title_block
		(title "03242023_DA0F0TMBIJ0_F0T_Motherboard_J_brd_V01_OCP.brd")
		(comment 1 "Grand Teton / footprints 1179-1180 of 6105")
	)
	(layers
		(0 "F.Cu" signal "TOP")
		(4 "In1.Cu" signal "GND")
		(6 "In2.Cu" signal "IN1")
		(8 "In3.Cu" signal "GND1")
		(10 "In4.Cu" signal "IN2")
		(12 "In5.Cu" signal "GND2")
		(14 "In6.Cu" signal "IN3")
		(16 "In7.Cu" signal "GND3")
		(18 "In8.Cu" signal "VCC")
		(20 "In9.Cu" signal "VCC1")
		(22 "In10.Cu" signal "GND4")
		(24 "In11.Cu" signal "IN4")
		(26 "In12.Cu" signal "GND5")
		(28 "In13.Cu" signal "IN5")
		(30 "In14.Cu" signal "GND6")
		(32 "In15.Cu" signal "IN6")
		(34 "In16.Cu" signal "GND7")
		(2 "B.Cu" signal "BOTTOM")
		(9 "F.Adhes" user "F.Adhesive")
		(11 "B.Adhes" user "B.Adhesive")
		(13 "F.Paste" user "Package Geometry/Pastemask Top")
		(15 "B.Paste" user "Package Geometry/Pastemask Bottom")
		(5 "F.SilkS" user "Ref Des/Silkscreen Top")
		(7 "B.SilkS" user "Ref Des/Silkscreen Bottom")
		(1 "F.Mask" user "Board Geometry/Soldermask Top")
		(3 "B.Mask" user "Board Geometry/Soldermask Bottom")
		(17 "Dwgs.User" user "User.Drawings")
		(19 "Cmts.User" user "User.Comments")
		(21 "Eco1.User" user "User.Eco1")
		(23 "Eco2.User" user "User.Eco2")
		(25 "Edge.Cuts" user "Board Geometry/Outline")
		(27 "Margin" user)
		(31 "F.CrtYd" user "Package Geometry/Place Bound Top")
		(29 "B.CrtYd" user "Package Geometry/Place Bound Bottom")
		(35 "F.Fab" user "Ref Des/Assembly Top")
		(33 "B.Fab" user "Ref Des/Assembly Bottom")
	)
	(footprint ""
		(layer "F.Cu")
		(at 19.707352 -167.170608 90)
		(property "Reference" "C1337"
			(at 0 0 90)
			(layer "F.SilkS")
			(hide yes)
			(effects
				(font
					(size 1.27 1.27)
				)
			)
		)
		(property "Value" ""
			(at 0 0 90)
			(layer "F.Fab")
			(effects
				(font
					(size 1.27 1.27)
				)
			)
		)
		(duplicate_pad_numbers_are_jumpers no)
		(fp_line
			(start 0.7874 -0.4064)
			(end 0.7874 0.4064)
			(stroke
				(width 0.1524)
				(type default)
			)
			(layer "F.SilkS")
		)
		(fp_line
			(start -0.7874 -0.4064)
			(end 0.7874 -0.4064)
			(stroke
				(width 0.1524)
				(type default)
			)
			(layer "F.SilkS")
		)
		(fp_line
			(start 0.7874 0.4064)
			(end -0.7874 0.4064)
			(stroke
				(width 0.1524)
				(type default)
			)
			(layer "F.SilkS")
		)
		(fp_line
			(start -0.7874 0.4064)
			(end -0.7874 -0.4064)
			(stroke
				(width 0.1524)
				(type default)
			)
			(layer "F.SilkS")
		)
		(fp_line
			(start -0.12065 -0.305054)
			(end -0.12065 -0.2794)
			(stroke
				(width 0.1)
				(type default)
			)
			(layer "F.Fab")
		)
		(fp_line
			(start -0.67945 -0.305054)
			(end -0.12065 -0.305054)
			(stroke
				(width 0.1)
				(type default)
			)
			(layer "F.Fab")
		)
		(fp_line
			(start 0.67945 -0.3048)
			(end 0.67945 0.3048)
			(stroke
				(width 0.1)
				(type default)
			)
			(layer "F.Fab")
		)
		(fp_line
			(start 0.12065 -0.3048)
			(end 0.67945 -0.3048)
			(stroke
				(width 0.1)
				(type default)
			)
			(layer "F.Fab")
		)
		(fp_line
			(start 0.12065 -0.2794)
			(end 0.12065 -0.3048)
			(stroke
				(width 0.1)
				(type default)
			)
			(layer "F.Fab")
		)
		(fp_line
			(start -0.12065 -0.2794)
			(end 0.12065 -0.2794)
			(stroke
				(width 0.1)
				(type default)
			)
			(layer "F.Fab")
		)
		(fp_line
			(start 0.120396 0.2794)
			(end -0.12065 0.2794)
			(stroke
				(width 0.1)
				(type default)
			)
			(layer "F.Fab")
		)
		(fp_line
			(start -0.12065 0.2794)
			(end -0.12065 0.3048)
			(stroke
				(width 0.1)
				(type default)
			)
			(layer "F.Fab")
		)
		(fp_line
			(start 0.67945 0.3048)
			(end 0.120396 0.3048)
			(stroke
				(width 0.1)
				(type default)
			)
			(layer "F.Fab")
		)
		(fp_line
			(start 0.120396 0.3048)
			(end 0.120396 0.2794)
			(stroke
				(width 0.1)
				(type default)
			)
			(layer "F.Fab")
		)
		(fp_line
			(start -0.12065 0.3048)
			(end -0.67945 0.3048)
			(stroke
				(width 0.1)
				(type default)
			)
			(layer "F.Fab")
		)
		(fp_line
			(start -0.67945 0.3048)
			(end -0.67945 -0.305054)
			(stroke
				(width 0.1)
				(type default)
			)
			(layer "F.Fab")
		)
		(pad "1" smd circle
			(at -0.40005 0 90)
			(size 0 0)
			(layers "F.Cu" "F.Mask" "F.Paste")
			(net "PVNN_TERM_CPU1")
		)
		(pad "2" smd circle
			(at 0.40005 0 90)
			(size 0 0)
			(layers "F.Cu" "F.Mask" "F.Paste")
			(net "GND")
		)
	)
	(footprint ""
		(layer "F.Cu")
		(at 360.544618 -343.902284 90)
		(property "Reference" "PC315"
			(at 0 0 90)
			(layer "F.SilkS")
			(hide yes)
			(effects
				(font
					(size 1.27 1.27)
				)
			)
		)
		(property "Value" ""
			(at 0 0 90)
			(layer "F.Fab")
			(effects
				(font
					(size 1.27 1.27)
				)
			)
		)
		(duplicate_pad_numbers_are_jumpers no)
		(fp_line
			(start -3.400044 1.249934)
			(end 3.400044 1.249934)
			(stroke
				(width 0.1524)
				(type default)
			)
			(layer "F.SilkS")
		)
		(fp_circle
			(center 0 1.249934)
			(end 0 4.649978)
			(stroke
				(width 0.1524)
				(type default)
			)
			(fill no)
			(layer "F.SilkS")
		)
		(fp_poly
			(pts
				(arc
					(start -3.400044 1.249934)
					(mid 0 4.649978)
					(end 3.400044 1.249934)
				)
			)
			(stroke
				(width 0)
				(type default)
			)
			(fill yes)
			(layer "F.SilkS")
		)
		(fp_circle
			(center 0 1.249934)
			(end 0 4.649978)
			(stroke
				(width 0.1)
				(type default)
			)
			(fill no)
			(layer "F.Fab")
		)
		(pad "1" thru_hole rect
			(at 0 0 90)
			(size 1.524 1.524)
			(drill 1.016)
			(layers "*.Cu" "*.Mask")
			(remove_unused_layers no)
			(net "SW_P12V_PVCCIN_CPU0_FLT")
			(clearance 0)
			(padstack
				(mode front_inner_back)
				(layer "Inner"
					(shape circle)
					(size 1.524 1.524)
					(clearance 0)
				)
				(layer "B.Cu"
					(shape rect)
					(size 1.524 1.524)
					(clearance 0)
				)
			)
		)
		(pad "2" thru_hole circle
			(at 0 2.500122 90)
			(size 1.524 1.524)
			(drill 1.016)
			(layers "*.Cu" "*.Mask")
			(remove_unused_layers no)
			(net "GND")
			(clearance 0)
		)
	)
)
